(kicad_pcb
	(version 20260206)
	(generator "pcbnew")
	(generator_version "10.0")
	(general
		(thickness 1.6)
		(legacy_teardrops no)
	)
	(paper "A4")
	(title_block
		(title "baseboard — 13948-1b.1110WZS1818.brd")
		(comment 1 "Honey Badger (Wiwynn) / footprints 2012-2018 of 2523")
	)
	(layers
		(0 "F.Cu" signal "TOP")
		(4 "In1.Cu" signal "L2GND")
		(6 "In2.Cu" signal "L3")
		(8 "In3.Cu" signal "L4VCC")
		(10 "In4.Cu" signal "L5VCC")
		(12 "In5.Cu" signal "L6")
		(14 "In6.Cu" signal "L7GND")
		(2 "B.Cu" signal "BOTTOM")
		(9 "F.Adhes" user "F.Adhesive")
		(11 "B.Adhes" user "B.Adhesive")
		(13 "F.Paste" user "Package Geometry/Pastemask Top")
		(15 "B.Paste" user "Package Geometry/Pastemask Bottom")
		(5 "F.SilkS" user "Ref Des/Silkscreen Top")
		(7 "B.SilkS" user "Ref Des/Silkscreen Bottom")
		(1 "F.Mask" user "Board Geometry/Soldermask Top")
		(3 "B.Mask" user "Board Geometry/Soldermask Bottom")
		(17 "Dwgs.User" user "User.Drawings")
		(19 "Cmts.User" user "User.Comments")
		(21 "Eco1.User" user "User.Eco1")
		(23 "Eco2.User" user "User.Eco2")
		(25 "Edge.Cuts" user "Board Geometry/Outline")
		(27 "Margin" user)
		(31 "F.CrtYd" user "Package Geometry/Place Bound Top")
		(29 "B.CrtYd" user "Package Geometry/Place Bound Bottom")
		(35 "F.Fab" user "Ref Des/Assembly Top")
		(33 "B.Fab" user "Ref Des/Assembly Bottom")
	)
	(footprint ""
		(layer "B.Cu")
		(at 124.09297 -98.298)
		(property "Reference" "SC1184"
			(at 0 0 0)
			(layer "B.SilkS")
			(hide yes)
			(effects
				(font
					(size 1.27 1.27)
				)
				(justify mirror)
			)
		)
		(property "Value" "SC1U6D3V1MX-GP"
			(at -1.9177 2.0193 0)
			(unlocked yes)
			(layer "B.Fab")
			(hide yes)
			(effects
				(font
					(size 1.016 1.016)
					(thickness 0.1524)
				)
				(justify mirror)
			)
		)
		(property "Device Type" "C0201H14"
			(at -1.9177 0.4953 0)
			(unlocked yes)
			(layer "B.Fab")
			(hide yes)
			(effects
				(font
					(size 1.016 1.016)
					(thickness 0.1524)
				)
				(justify mirror)
			)
		)
		(duplicate_pad_numbers_are_jumpers no)
		(fp_rect
			(start 0.1524 0.3048)
			(end -0.1524 -0.3048)
			(stroke
				(width 0)
				(type default)
			)
			(fill no)
			(layer "B.CrtYd")
		)
		(fp_poly
			(pts
				(xy 0.2794 0.6477) (xy 0.2794 -0.6477) (xy -0.2794 -0.6477) (xy -0.2794 -0.1905) (xy -0.1524 -0.1905)
				(xy -0.1524 -0.3048) (xy 0.1524 -0.3048) (xy 0.1524 0.3048) (xy -0.1524 0.3048) (xy -0.1524 -0.1778)
				(xy -0.2794 -0.1778) (xy -0.2794 0.6477)
			)
			(stroke
				(width 0)
				(type default)
			)
			(fill no)
			(layer "B.CrtYd")
		)
		(fp_rect
			(start 0.2794 0.6477)
			(end -0.2794 -0.6477)
			(stroke
				(width 0)
				(type default)
			)
			(fill no)
			(layer "B.Fab")
		)
		(pad "1" smd custom
			(at 0 -0.2794 180)
			(size 0.0762 0.0762)
			(layers "B.Cu" "B.Mask" "B.Paste")
			(net "GB_VDDA")
			(options
				(clearance outline)
				(anchor circle)
			)
			(primitives
				(gr_poly
					(pts
						(arc
							(start 0.1524 0.127)
							(mid 0.137521 0.162921)
							(end 0.1016 0.1778)
						)
						(arc
							(start -0.1016 0.1778)
							(mid -0.137521 0.162921)
							(end -0.1524 0.127)
						)
						(arc
							(start -0.1524 -0.127)
							(mid -0.137521 -0.162921)
							(end -0.1016 -0.1778)
						)
						(arc
							(start 0.1016 -0.1778)
							(mid 0.137521 -0.162921)
							(end 0.1524 -0.127)
						)
					)
					(width 0)
					(fill yes)
				)
			)
		)
		(pad "2" smd custom
			(at 0 0.2794 180)
			(size 0.0762 0.0762)
			(layers "B.Cu" "B.Mask" "B.Paste")
			(net "GND")
			(options
				(clearance outline)
				(anchor circle)
			)
			(primitives
				(gr_poly
					(pts
						(arc
							(start 0.1524 0.127)
							(mid 0.137521 0.162921)
							(end 0.1016 0.1778)
						)
						(arc
							(start -0.1016 0.1778)
							(mid -0.137521 0.162921)
							(end -0.1524 0.127)
						)
						(arc
							(start -0.1524 -0.127)
							(mid -0.137521 -0.162921)
							(end -0.1016 -0.1778)
						)
						(arc
							(start 0.1016 -0.1778)
							(mid 0.137521 -0.162921)
							(end 0.1524 -0.127)
						)
					)
					(width 0)
					(fill yes)
				)
			)
		)
	)
	(footprint ""
		(layer "B.Cu")
		(at 43.12793 -77.650086)
		(property "Reference" "SC1275"
			(at 0 0 0)
			(layer "B.SilkS")
			(hide yes)
			(effects
				(font
					(size 1.27 1.27)
				)
				(justify mirror)
			)
		)
		(property "Value" "SCD01U50V2KX-1GP"
			(at -1.1811 -2.7051 0)
			(unlocked yes)
			(layer "B.Fab")
			(hide yes)
			(effects
				(font
					(size 1.016 1.016)
					(thickness 0.1524)
				)
				(justify mirror)
			)
		)
		(property "Device Type" "C402H22"
			(at -1.1811 -4.2291 0)
			(unlocked yes)
			(layer "B.Fab")
			(hide yes)
			(effects
				(font
					(size 1.016 1.016)
					(thickness 0.1524)
				)
				(justify mirror)
			)
		)
		(duplicate_pad_numbers_are_jumpers no)
		(fp_rect
			(start 0.4318 0.9525)
			(end -0.4318 -0.9525)
			(stroke
				(width 0)
				(type default)
			)
			(fill no)
			(layer "B.CrtYd")
		)
		(fp_rect
			(start 0.4318 0.9525)
			(end -0.4318 -0.9525)
			(stroke
				(width 0)
				(type default)
			)
			(fill no)
			(layer "B.Fab")
		)
		(pad "1" smd custom
			(at 0 -0.4445 180)
			(size 0.1524 0.1524)
			(layers "B.Cu" "B.Mask" "B.Paste")
			(net "SAS_EXP2CONN_RX_N_20")
			(options
				(clearance outline)
				(anchor circle)
			)
			(primitives
				(gr_poly
					(pts
						(arc
							(start 0.3048 0.2032)
							(mid 0.275042 0.275042)
							(end 0.2032 0.3048)
						)
						(arc
							(start -0.2032 0.3048)
							(mid -0.275042 0.275042)
							(end -0.3048 0.2032)
						)
						(arc
							(start -0.3048 -0.2032)
							(mid -0.275042 -0.275042)
							(end -0.2032 -0.3048)
						)
						(arc
							(start 0.2032 -0.3048)
							(mid 0.275042 -0.275042)
							(end 0.3048 -0.2032)
						)
					)
					(width 0)
					(fill yes)
				)
			)
		)
		(pad "2" smd custom
			(at 0 0.4445 180)
			(size 0.1524 0.1524)
			(layers "B.Cu" "B.Mask" "B.Paste")
			(net "MINI_RX_N_20")
			(options
				(clearance outline)
				(anchor circle)
			)
			(primitives
				(gr_poly
					(pts
						(arc
							(start 0.3048 0.2032)
							(mid 0.275042 0.275042)
							(end 0.2032 0.3048)
						)
						(arc
							(start -0.2032 0.3048)
							(mid -0.275042 0.275042)
							(end -0.3048 0.2032)
						)
						(arc
							(start -0.3048 -0.2032)
							(mid -0.275042 -0.275042)
							(end -0.2032 -0.3048)
						)
						(arc
							(start 0.2032 -0.3048)
							(mid 0.275042 -0.275042)
							(end 0.3048 -0.2032)
						)
					)
					(width 0)
					(fill yes)
				)
			)
		)
	)
	(footprint ""
		(layer "B.Cu")
		(at 105.796842 -82.875882 -90)
		(property "Reference" "SR768"
			(at 0 0 90)
			(layer "B.SilkS")
			(hide yes)
			(effects
				(font
					(size 1.27 1.27)
				)
				(justify mirror)
			)
		)
		(property "Value" "4K75R2F-1-GP"
			(at -0.064008 -3.993896 270)
			(unlocked yes)
			(layer "B.Fab")
			(hide yes)
			(effects
				(font
					(size 1.016 1.016)
					(thickness 0.1524)
				)
				(justify mirror)
			)
		)
		(property "Device Type" "R402H16"
			(at -0.064008 -5.517896 270)
			(unlocked yes)
			(layer "B.Fab")
			(hide yes)
			(effects
				(font
					(size 1.016 1.016)
					(thickness 0.1524)
				)
				(justify mirror)
			)
		)
		(duplicate_pad_numbers_are_jumpers no)
		(fp_line
			(start -0.508 -0.9398)
			(end 0.508 -0.9398)
			(stroke
				(width 0.1524)
				(type default)
			)
			(layer "B.SilkS")
		)
		(fp_line
			(start 0.508 -0.9398)
			(end 0.508 0.9398)
			(stroke
				(width 0.1524)
				(type default)
			)
			(layer "B.SilkS")
		)
		(fp_rect
			(start 0.508 0.9398)
			(end -0.508 -0.9398)
			(stroke
				(width 0)
				(type default)
			)
			(fill no)
			(layer "B.CrtYd")
		)
		(fp_rect
			(start 0.508 0.9398)
			(end -0.508 -0.9398)
			(stroke
				(width 0)
				(type default)
			)
			(fill no)
			(layer "B.Fab")
		)
		(pad "1" smd custom
			(at 0 -0.4445 90)
			(size 0.1397 0.1397)
			(layers "B.Cu" "B.Mask" "B.Paste")
			(net "GND")
			(options
				(clearance outline)
				(anchor circle)
			)
			(primitives
				(gr_poly
					(pts
						(arc
							(start -0.1778 0.2794)
							(mid -0.249642 0.249642)
							(end -0.2794 0.1778)
						)
						(arc
							(start -0.2794 -0.1778)
							(mid -0.249642 -0.249642)
							(end -0.1778 -0.2794)
						)
						(arc
							(start 0.1778 -0.2794)
							(mid 0.249642 -0.249642)
							(end 0.2794 -0.1778)
						)
						(arc
							(start 0.2794 0.1778)
							(mid 0.249642 0.249642)
							(end 0.1778 0.2794)
						)
					)
					(width 0)
					(fill yes)
				)
			)
		)
		(pad "2" smd custom
			(at 0 0.4445 90)
			(size 0.1397 0.1397)
			(layers "B.Cu" "B.Mask" "B.Paste")
			(net "EXP_BLINK_IN")
			(options
				(clearance outline)
				(anchor circle)
			)
			(primitives
				(gr_poly
					(pts
						(arc
							(start -0.1778 0.2794)
							(mid -0.249642 0.249642)
							(end -0.2794 0.1778)
						)
						(arc
							(start -0.2794 -0.1778)
							(mid -0.249642 -0.249642)
							(end -0.1778 -0.2794)
						)
						(arc
							(start 0.1778 -0.2794)
							(mid 0.249642 -0.249642)
							(end 0.2794 -0.1778)
						)
						(arc
							(start 0.2794 0.1778)
							(mid 0.249642 0.249642)
							(end 0.1778 0.2794)
						)
					)
					(width 0)
					(fill yes)
				)
			)
		)
	)
	(footprint ""
		(layer "B.Cu")
		(at 99.822 -239.395)
		(property "Reference" "SR843"
			(at 0 0 0)
			(layer "B.SilkS")
			(hide yes)
			(effects
				(font
					(size 1.27 1.27)
				)
				(justify mirror)
			)
		)
		(property "Value" "4K7R2F-GP"
			(at -0.064008 -3.993896 0)
			(unlocked yes)
			(layer "B.Fab")
			(hide yes)
			(effects
				(font
					(size 1.016 1.016)
					(thickness 0.1524)
				)
				(justify mirror)
			)
		)
		(property "Device Type" "R402H16"
			(at -0.064008 -5.517896 0)
			(unlocked yes)
			(layer "B.Fab")
			(hide yes)
			(effects
				(font
					(size 1.016 1.016)
					(thickness 0.1524)
				)
				(justify mirror)
			)
		)
		(duplicate_pad_numbers_are_jumpers no)
		(fp_line
			(start -0.508 -0.9398)
			(end 0.508 -0.9398)
			(stroke
				(width 0.1524)
				(type default)
			)
			(layer "B.SilkS")
		)
		(fp_line
			(start 0.508 -0.9398)
			(end 0.508 0.9398)
			(stroke
				(width 0.1524)
				(type default)
			)
			(layer "B.SilkS")
		)
		(fp_rect
			(start 0.508 0.9398)
			(end -0.508 -0.9398)
			(stroke
				(width 0)
				(type default)
			)
			(fill no)
			(layer "B.CrtYd")
		)
		(fp_rect
			(start 0.508 0.9398)
			(end -0.508 -0.9398)
			(stroke
				(width 0)
				(type default)
			)
			(fill no)
			(layer "B.Fab")
		)
		(pad "1" smd custom
			(at 0 -0.4445 180)
			(size 0.1397 0.1397)
			(layers "B.Cu" "B.Mask" "B.Paste")
			(net "SAS_FAULT_LED0")
			(options
				(clearance outline)
				(anchor circle)
			)
			(primitives
				(gr_poly
					(pts
						(arc
							(start -0.1778 0.2794)
							(mid -0.249642 0.249642)
							(end -0.2794 0.1778)
						)
						(arc
							(start -0.2794 -0.1778)
							(mid -0.249642 -0.249642)
							(end -0.1778 -0.2794)
						)
						(arc
							(start 0.1778 -0.2794)
							(mid 0.249642 -0.249642)
							(end 0.2794 -0.1778)
						)
						(arc
							(start 0.2794 0.1778)
							(mid 0.249642 0.249642)
							(end 0.1778 0.2794)
						)
					)
					(width 0)
					(fill yes)
				)
			)
		)
		(pad "2" smd custom
			(at 0 0.4445 180)
			(size 0.1397 0.1397)
			(layers "B.Cu" "B.Mask" "B.Paste")
			(net "P3V3_STBY")
			(options
				(clearance outline)
				(anchor circle)
			)
			(primitives
				(gr_poly
					(pts
						(arc
							(start -0.1778 0.2794)
							(mid -0.249642 0.249642)
							(end -0.2794 0.1778)
						)
						(arc
							(start -0.2794 -0.1778)
							(mid -0.249642 -0.249642)
							(end -0.1778 -0.2794)
						)
						(arc
							(start 0.1778 -0.2794)
							(mid 0.249642 -0.249642)
							(end 0.2794 -0.1778)
						)
						(arc
							(start 0.2794 0.1778)
							(mid 0.249642 0.249642)
							(end 0.1778 0.2794)
						)
					)
					(width 0)
					(fill yes)
				)
			)
		)
	)
	(footprint ""
		(layer "B.Cu")
		(at 86.233 -74.041 90)
		(property "Reference" "SQ11"
			(at 0 0 90)
			(layer "B.SilkS")
			(hide yes)
			(effects
				(font
					(size 1.27 1.27)
				)
				(justify mirror)
			)
		)
		(property "Value" "2N7002A-7-GP"
			(at -0.127 -8.9662 90)
			(unlocked yes)
			(layer "B.Fab")
			(hide yes)
			(effects
				(font
					(size 1.016 1.016)
					(thickness 0.1524)
				)
				(justify mirror)
			)
		)
		(property "Device Type" "SOT23DGS2D4H48"
			(at -0.127 -10.4902 90)
			(unlocked yes)
			(layer "B.Fab")
			(hide yes)
			(effects
				(font
					(size 1.016 1.016)
					(thickness 0.1524)
				)
				(justify mirror)
			)
		)
		(duplicate_pad_numbers_are_jumpers no)
		(fp_line
			(start 1.651 -1.778)
			(end 1.651 1.778)
			(stroke
				(width 0.1524)
				(type default)
			)
			(layer "B.SilkS")
		)
		(fp_line
			(start -1.651 -1.778)
			(end 1.651 -1.778)
			(stroke
				(width 0.1524)
				(type default)
			)
			(layer "B.SilkS")
		)
		(fp_line
			(start 1.651 1.778)
			(end -1.651 1.778)
			(stroke
				(width 0.1524)
				(type default)
			)
			(layer "B.SilkS")
		)
		(fp_line
			(start -1.651 1.778)
			(end -1.651 -1.778)
			(stroke
				(width 0.1524)
				(type default)
			)
			(layer "B.SilkS")
		)
		(fp_poly
			(pts
				(xy 1.778 1.8796) (xy 1.778 -1.8796) (xy -1.778 -1.8796) (xy -1.778 1.8796)
			)
			(stroke
				(width 0)
				(type default)
			)
			(fill no)
			(layer "B.CrtYd")
		)
		(fp_poly
			(pts
				(xy 1.778 1.8796) (xy 1.778 -1.8796) (xy -1.778 -1.8796) (xy -1.778 1.8796)
			)
			(stroke
				(width 0)
				(type default)
			)
			(fill no)
			(layer "B.Fab")
		)
		(pad "D" smd custom
			(at 0 -0.9525 270)
			(size 0.1905 0.1905)
			(layers "B.Cu" "B.Mask" "B.Paste")
			(net "P0V955_C_PG_R")
			(options
				(clearance outline)
				(anchor circle)
			)
			(primitives
				(gr_poly
					(pts
						(arc
							(start -0.1778 -0.5715)
							(mid -0.321484 -0.511984)
							(end -0.381 -0.3683)
						)
						(arc
							(start -0.381 0.3683)
							(mid -0.321484 0.511984)
							(end -0.1778 0.5715)
						)
						(arc
							(start 0.1778 0.5715)
							(mid 0.321484 0.511984)
							(end 0.381 0.3683)
						)
						(arc
							(start 0.381 -0.3683)
							(mid 0.321484 -0.511984)
							(end 0.1778 -0.5715)
						)
					)
					(width 0)
					(fill yes)
				)
			)
		)
		(pad "G" smd custom
			(at 0.98425 0.9525 270)
			(size 0.1905 0.1905)
			(layers "B.Cu" "B.Mask" "B.Paste")
			(net "P3V3_STBY_G9")
			(options
				(clearance outline)
				(anchor circle)
			)
			(primitives
				(gr_poly
					(pts
						(arc
							(start -0.1778 -0.5715)
							(mid -0.321484 -0.511984)
							(end -0.381 -0.3683)
						)
						(arc
							(start -0.381 0.3683)
							(mid -0.321484 0.511984)
							(end -0.1778 0.5715)
						)
						(arc
							(start 0.1778 0.5715)
							(mid 0.321484 0.511984)
							(end 0.381 0.3683)
						)
						(arc
							(start 0.381 -0.3683)
							(mid 0.321484 -0.511984)
							(end 0.1778 -0.5715)
						)
					)
					(width 0)
					(fill yes)
				)
			)
		)
		(pad "S" smd custom
			(at -0.98425 0.9525 270)
			(size 0.1905 0.1905)
			(layers "B.Cu" "B.Mask" "B.Paste")
			(net "GND")
			(options
				(clearance outline)
				(anchor circle)
			)
			(primitives
				(gr_poly
					(pts
						(arc
							(start -0.1778 -0.5715)
							(mid -0.321484 -0.511984)
							(end -0.381 -0.3683)
						)
						(arc
							(start -0.381 0.3683)
							(mid -0.321484 0.511984)
							(end -0.1778 0.5715)
						)
						(arc
							(start 0.1778 0.5715)
							(mid 0.321484 0.511984)
							(end 0.381 0.3683)
						)
						(arc
							(start 0.381 -0.3683)
							(mid 0.321484 -0.511984)
							(end 0.1778 -0.5715)
						)
					)
					(width 0)
					(fill yes)
				)
			)
		)
	)
	(footprint ""
		(layer "B.Cu")
		(at 290.9316 -170.9674)
		(property "Reference" "TP85"
			(at 0 0 0)
			(layer "B.SilkS")
			(hide yes)
			(effects
				(font
					(size 1.27 1.27)
				)
				(justify mirror)
			)
		)
		(property "Value" "TPAD28"
			(at 0.0127 -1.6637 0)
			(unlocked yes)
			(layer "B.Fab")
			(hide yes)
			(effects
				(font
					(size 1.016 1.016)
					(thickness 0.1524)
				)
				(justify mirror)
			)
		)
		(property "Device Type" "TPAD28"
			(at 0.0127 -3.1877 0)
			(unlocked yes)
			(layer "B.Fab")
			(hide yes)
			(effects
				(font
					(size 1.016 1.016)
					(thickness 0.1524)
				)
				(justify mirror)
			)
		)
		(duplicate_pad_numbers_are_jumpers no)
		(fp_poly
			(pts
				(arc
					(start 0.3556 0)
					(mid -0.3556 0)
					(end 0.3556 0)
				)
			)
			(stroke
				(width 0)
				(type default)
			)
			(fill no)
			(layer "B.CrtYd")
		)
		(fp_poly
			(pts
				(arc
					(start 0.6096 0)
					(mid -0.6096 0)
					(end 0.6096 0)
				)
			)
			(stroke
				(width 0)
				(type default)
			)
			(fill no)
			(layer "B.Fab")
		)
		(pad "1" smd circle
			(at 0 0 180)
			(size 0.7112 0.7112)
			(layers "B.Cu" "B.Mask" "B.Paste")
			(net "BMC0_TP15")
		)
	)
	(footprint ""
		(layer "B.Cu")
		(at 108.336842 -82.621882 180)
		(property "Reference" "SR770"
			(at 0 0 0)
			(layer "B.SilkS")
			(hide yes)
			(effects
				(font
					(size 1.27 1.27)
				)
				(justify mirror)
			)
		)
		(property "Value" "4K75R2F-1-GP"
			(at -0.064008 -3.993896 180)
			(unlocked yes)
			(layer "B.Fab")
			(hide yes)
			(effects
				(font
					(size 1.016 1.016)
					(thickness 0.1524)
				)
				(justify mirror)
			)
		)
		(property "Device Type" "R402H16"
			(at -0.064008 -5.517896 180)
			(unlocked yes)
			(layer "B.Fab")
			(hide yes)
			(effects
				(font
					(size 1.016 1.016)
					(thickness 0.1524)
				)
				(justify mirror)
			)
		)
		(duplicate_pad_numbers_are_jumpers no)
		(fp_line
			(start 0.508 -0.9398)
			(end 0.508 0.9398)
			(stroke
				(width 0.1524)
				(type default)
			)
			(layer "B.SilkS")
		)
		(fp_line
			(start -0.508 -0.9398)
			(end 0.508 -0.9398)
			(stroke
				(width 0.1524)
				(type default)
			)
			(layer "B.SilkS")
		)
		(fp_rect
			(start 0.508 0.9398)
			(end -0.508 -0.9398)
			(stroke
				(width 0)
				(type default)
			)
			(fill no)
			(layer "B.CrtYd")
		)
		(fp_rect
			(start 0.508 0.9398)
			(end -0.508 -0.9398)
			(stroke
				(width 0)
				(type default)
			)
			(fill no)
			(layer "B.Fab")
		)
		(pad "1" smd custom
			(at 0 -0.4445)
			(size 0.1397 0.1397)
			(layers "B.Cu" "B.Mask" "B.Paste")
			(net "GND")
			(options
				(clearance outline)
				(anchor circle)
			)
			(primitives
				(gr_poly
					(pts
						(arc
							(start -0.1778 0.2794)
							(mid -0.249642 0.249642)
							(end -0.2794 0.1778)
						)
						(arc
							(start -0.2794 -0.1778)
							(mid -0.249642 -0.249642)
							(end -0.1778 -0.2794)
						)
						(arc
							(start 0.1778 -0.2794)
							(mid 0.249642 -0.249642)
							(end 0.2794 -0.1778)
						)
						(arc
							(start 0.2794 0.1778)
							(mid 0.249642 0.249642)
							(end 0.1778 0.2794)
						)
					)
					(width 0)
					(fill yes)
				)
			)
		)
		(pad "2" smd custom
			(at 0 0.4445)
			(size 0.1397 0.1397)
			(layers "B.Cu" "B.Mask" "B.Paste")
			(net "EXP_ADC_IN1")
			(options
				(clearance outline)
				(anchor circle)
			)
			(primitives
				(gr_poly
					(pts
						(arc
							(start -0.1778 0.2794)
							(mid -0.249642 0.249642)
							(end -0.2794 0.1778)
						)
						(arc
							(start -0.2794 -0.1778)
							(mid -0.249642 -0.249642)
							(end -0.1778 -0.2794)
						)
						(arc
							(start 0.1778 -0.2794)
							(mid 0.249642 -0.249642)
							(end 0.2794 -0.1778)
						)
						(arc
							(start 0.2794 0.1778)
							(mid 0.249642 0.249642)
							(end 0.1778 0.2794)
						)
					)
					(width 0)
					(fill yes)
				)
			)
		)
	)
)
